# S9S_MB_2U (Grand Teton) — schematic netlist excerpt (pin names and nets, part order shuffled) for the footprints in the layout excerpt that follows; sources: Cadence DE-HDL packaged netlist, KiCad conversion of 03242023_DA0F0TMBIJ0_F0T_Motherboard_J_brd_V01_OCP.brd

R1130  Q_RES  33.2 1% CHIP  pkg 0402LF  page 158 : A = SMB_PEHPCPU0_LVC3_SCL ; B = SMB_PEHPCPU0_LVC3_R_SCL
R4894  Q_RES  0 5% EMPTY  pkg 0402LF  page 305 : A = P12V_HSC_TEMP_SCL ; B = SMB_LM75_0_3V3AUX_SCL

(kicad_pcb
	(version 20260206)
	(generator "pcbnew")
	(generator_version "10.0")
	(general
		(thickness 1.6)
		(legacy_teardrops no)
	)
	(paper "A4")
	(title_block
		(title "03242023_DA0F0TMBIJ0_F0T_Motherboard_J_brd_V01_OCP.brd")
		(comment 1 "Grand Teton / footprints 2902-2903 of 6105")
	)
	(layers
		(0 "F.Cu" signal "TOP")
		(4 "In1.Cu" signal "GND")
		(6 "In2.Cu" signal "IN1")
		(8 "In3.Cu" signal "GND1")
		(10 "In4.Cu" signal "IN2")
		(12 "In5.Cu" signal "GND2")
		(14 "In6.Cu" signal "IN3")
		(16 "In7.Cu" signal "GND3")
		(18 "In8.Cu" signal "VCC")
		(20 "In9.Cu" signal "VCC1")
		(22 "In10.Cu" signal "GND4")
		(24 "In11.Cu" signal "IN4")
		(26 "In12.Cu" signal "GND5")
		(28 "In13.Cu" signal "IN5")
		(30 "In14.Cu" signal "GND6")
		(32 "In15.Cu" signal "IN6")
		(34 "In16.Cu" signal "GND7")
		(2 "B.Cu" signal "BOTTOM")
		(9 "F.Adhes" user "F.Adhesive")
		(11 "B.Adhes" user "B.Adhesive")
		(13 "F.Paste" user "Package Geometry/Pastemask Top")
		(15 "B.Paste" user "Package Geometry/Pastemask Bottom")
		(5 "F.SilkS" user "Ref Des/Silkscreen Top")
		(7 "B.SilkS" user "Ref Des/Silkscreen Bottom")
		(1 "F.Mask" user "Board Geometry/Soldermask Top")
		(3 "B.Mask" user "Board Geometry/Soldermask Bottom")
		(17 "Dwgs.User" user "User.Drawings")
		(19 "Cmts.User" user "User.Comments")
		(21 "Eco1.User" user "User.Eco1")
		(23 "Eco2.User" user "User.Eco2")
		(25 "Edge.Cuts" user "Board Geometry/Outline")
		(27 "Margin" user)
		(31 "F.CrtYd" user "Package Geometry/Place Bound Top")
		(29 "B.CrtYd" user "Package Geometry/Place Bound Bottom")
		(35 "F.Fab" user "Ref Des/Assembly Top")
		(33 "B.Fab" user "Ref Des/Assembly Bottom")
	)
	(footprint ""
		(layer "F.Cu")
		(at 465.821014 -117.651022 180)
		(property "Reference" "R1130"
			(at 0 0 180)
			(layer "F.SilkS")
			(hide yes)
			(effects
				(font
					(size 1.27 1.27)
				)
			)
		)
		(property "Value" ""
			(at 0 0 180)
			(layer "F.Fab")
			(effects
				(font
					(size 1.27 1.27)
				)
			)
		)
		(duplicate_pad_numbers_are_jumpers no)
		(fp_line
			(start 0.7874 0.4064)
			(end -0.7874 0.4064)
			(stroke
				(width 0.1524)
				(type default)
			)
			(layer "F.SilkS")
		)
		(fp_line
			(start 0.7874 -0.4064)
			(end 0.7874 0.4064)
			(stroke
				(width 0.1524)
				(type default)
			)
			(layer "F.SilkS")
		)
		(fp_line
			(start -0.7874 0.4064)
			(end -0.7874 -0.4064)
			(stroke
				(width 0.1524)
				(type default)
			)
			(layer "F.SilkS")
		)
		(fp_line
			(start -0.7874 -0.4064)
			(end 0.7874 -0.4064)
			(stroke
				(width 0.1524)
				(type default)
			)
			(layer "F.SilkS")
		)
		(fp_line
			(start 0.67945 0.3048)
			(end 0.120396 0.3048)
			(stroke
				(width 0.1)
				(type default)
			)
			(layer "F.Fab")
		)
		(fp_line
			(start 0.67945 -0.3048)
			(end 0.67945 0.3048)
			(stroke
				(width 0.1)
				(type default)
			)
			(layer "F.Fab")
		)
		(fp_line
			(start 0.12065 -0.2794)
			(end 0.12065 -0.3048)
			(stroke
				(width 0.1)
				(type default)
			)
			(layer "F.Fab")
		)
		(fp_line
			(start 0.12065 -0.3048)
			(end 0.67945 -0.3048)
			(stroke
				(width 0.1)
				(type default)
			)
			(layer "F.Fab")
		)
		(fp_line
			(start 0.120396 0.3048)
			(end 0.120396 0.2794)
			(stroke
				(width 0.1)
				(type default)
			)
			(layer "F.Fab")
		)
		(fp_line
			(start 0.120396 0.2794)
			(end -0.12065 0.2794)
			(stroke
				(width 0.1)
				(type default)
			)
			(layer "F.Fab")
		)
		(fp_line
			(start -0.12065 0.3048)
			(end -0.67945 0.3048)
			(stroke
				(width 0.1)
				(type default)
			)
			(layer "F.Fab")
		)
		(fp_line
			(start -0.12065 0.2794)
			(end -0.12065 0.3048)
			(stroke
				(width 0.1)
				(type default)
			)
			(layer "F.Fab")
		)
		(fp_line
			(start -0.12065 -0.2794)
			(end 0.12065 -0.2794)
			(stroke
				(width 0.1)
				(type default)
			)
			(layer "F.Fab")
		)
		(fp_line
			(start -0.12065 -0.305054)
			(end -0.12065 -0.2794)
			(stroke
				(width 0.1)
				(type default)
			)
			(layer "F.Fab")
		)
		(fp_line
			(start -0.67945 0.3048)
			(end -0.67945 -0.305054)
			(stroke
				(width 0.1)
				(type default)
			)
			(layer "F.Fab")
		)
		(fp_line
			(start -0.67945 -0.305054)
			(end -0.12065 -0.305054)
			(stroke
				(width 0.1)
				(type default)
			)
			(layer "F.Fab")
		)
		(pad "1" smd circle
			(at -0.40005 0 180)
			(size 0 0)
			(layers "F.Cu" "F.Mask" "F.Paste")
			(net "SMB_PEHPCPU0_LVC3_SCL")
		)
		(pad "2" smd circle
			(at 0.40005 0 180)
			(size 0 0)
			(layers "F.Cu" "F.Mask" "F.Paste")
			(net "SMB_PEHPCPU0_LVC3_R_SCL")
		)
	)
	(footprint ""
		(layer "F.Cu")
		(at 298.13504 -409.69184)
		(property "Reference" "R4894"
			(at 0 0 0)
			(layer "F.SilkS")
			(hide yes)
			(effects
				(font
					(size 1.27 1.27)
				)
			)
		)
		(property "Value" ""
			(at 0 0 0)
			(layer "F.Fab")
			(effects
				(font
					(size 1.27 1.27)
				)
			)
		)
		(duplicate_pad_numbers_are_jumpers no)
		(fp_line
			(start -0.7874 -0.4064)
			(end 0.7874 -0.4064)
			(stroke
				(width 0.1524)
				(type default)
			)
			(layer "F.SilkS")
		)
		(fp_line
			(start -0.7874 0.4064)
			(end -0.7874 -0.4064)
			(stroke
				(width 0.1524)
				(type default)
			)
			(layer "F.SilkS")
		)
		(fp_line
			(start 0.7874 -0.4064)
			(end 0.7874 0.4064)
			(stroke
				(width 0.1524)
				(type default)
			)
			(layer "F.SilkS")
		)
		(fp_line
			(start 0.7874 0.4064)
			(end -0.7874 0.4064)
			(stroke
				(width 0.1524)
				(type default)
			)
			(layer "F.SilkS")
		)
		(fp_line
			(start -0.67945 -0.305054)
			(end -0.12065 -0.305054)
			(stroke
				(width 0.1)
				(type default)
			)
			(layer "F.Fab")
		)
		(fp_line
			(start -0.67945 0.3048)
			(end -0.67945 -0.305054)
			(stroke
				(width 0.1)
				(type default)
			)
			(layer "F.Fab")
		)
		(fp_line
			(start -0.12065 -0.305054)
			(end -0.12065 -0.2794)
			(stroke
				(width 0.1)
				(type default)
			)
			(layer "F.Fab")
		)
		(fp_line
			(start -0.12065 -0.2794)
			(end 0.12065 -0.2794)
			(stroke
				(width 0.1)
				(type default)
			)
			(layer "F.Fab")
		)
		(fp_line
			(start -0.12065 0.2794)
			(end -0.12065 0.3048)
			(stroke
				(width 0.1)
				(type default)
			)
			(layer "F.Fab")
		)
		(fp_line
			(start -0.12065 0.3048)
			(end -0.67945 0.3048)
			(stroke
				(width 0.1)
				(type default)
			)
			(layer "F.Fab")
		)
		(fp_line
			(start 0.120396 0.2794)
			(end -0.12065 0.2794)
			(stroke
				(width 0.1)
				(type default)
			)
			(layer "F.Fab")
		)
		(fp_line
			(start 0.120396 0.3048)
			(end 0.120396 0.2794)
			(stroke
				(width 0.1)
				(type default)
			)
			(layer "F.Fab")
		)
		(fp_line
			(start 0.12065 -0.3048)
			(end 0.67945 -0.3048)
			(stroke
				(width 0.1)
				(type default)
			)
			(layer "F.Fab")
		)
		(fp_line
			(start 0.12065 -0.2794)
			(end 0.12065 -0.3048)
			(stroke
				(width 0.1)
				(type default)
			)
			(layer "F.Fab")
		)
		(fp_line
			(start 0.67945 -0.3048)
			(end 0.67945 0.3048)
			(stroke
				(width 0.1)
				(type default)
			)
			(layer "F.Fab")
		)
		(fp_line
			(start 0.67945 0.3048)
			(end 0.120396 0.3048)
			(stroke
				(width 0.1)
				(type default)
			)
			(layer "F.Fab")
		)
		(pad "1" smd circle
			(at -0.40005 0)
			(size 0 0)
			(layers "F.Cu" "F.Mask" "F.Paste")
			(net "P12V_HSC_TEMP_SCL")
		)
		(pad "2" smd circle
			(at 0.40005 0)
			(size 0 0)
			(layers "F.Cu" "F.Mask" "F.Paste")
			(net "SMB_LM75_0_3V3AUX_SCL")
		)
	)
)
